FILE_TYPE=LIBRARY_PARTS;
primitive 'SN74AVC2T245RSWR';
  pin
    'DIR2':
      PIN_NUMBER='(1)';
      INPUT_LOAD='(-0.01,0.01)';
    'OE_#':
      PIN_NUMBER='(2)';
      INPUT_LOAD='(-0.01,0.01)';
    'GND':
      PIN_NUMBER='(3)';
      PINUSE='POWER';
      NO_LOAD_CHECK='Both';
      NO_IO_CHECK='Both';
      NO_ASSERT_CHECK='TRUE';
      NO_DIR_CHECK='TRUE';
      ALLOW_CONNECT='TRUE';
    'B2':
      PIN_NUMBER='(4)';
      OUTPUT_LOAD='(1.0,-1.0)';
    'B1':
      PIN_NUMBER='(5)';
      OUTPUT_LOAD='(1.0,-1.0)';
    'VCCB':
      PIN_NUMBER='(6)';
      PINUSE='POWER';
      NO_LOAD_CHECK='Both';
      NO_IO_CHECK='Both';
      NO_ASSERT_CHECK='TRUE';
      NO_DIR_CHECK='TRUE';
      ALLOW_CONNECT='TRUE';
    'VCCA':
      PIN_NUMBER='(7)';
      PINUSE='POWER';
      NO_LOAD_CHECK='Both';
      NO_IO_CHECK='Both';
      NO_ASSERT_CHECK='TRUE';
      NO_DIR_CHECK='TRUE';
      ALLOW_CONNECT='TRUE';
    'A1':
      PIN_NUMBER='(8)';
      INPUT_LOAD='(-0.01,0.01)';
    'A2':
      PIN_NUMBER='(9)';
      INPUT_LOAD='(-0.01,0.01)';
    'DIR1':
      PIN_NUMBER='(10)';
      INPUT_LOAD='(-0.01,0.01)';
  end_pin;
  body
    PART_NAME='SN74AVC2T245RSWR';
    BODY_NAME='SN74AVC2T245RSWR';
    PHYS_DES_PREFIX='U';
    CLASS='IC';
  end_body;
end_primitive;

END.
